# T6G (Grand Teton) — schematic netlist excerpt (pin names and nets, part order shuffled) for the footprints in the layout excerpt that follows; sources: Cadence DE-HDL packaged netlist, KiCad conversion of 04192023_DAF0TMB3IC0_F0TG_MB_C_brd_V02_OCP.brd

PR6532  Q_RES  49.9 1% CHIP  pkg 0402LF  page 362 : A = P0V9_RETIMER_CPU0_SENSE_SH_N ; B = GND
PC414  Q_CAP  0.22UF 16V 10% X7R  pkg 0402  page 219 : A = SW_PVDDCR_CPU1_P1_BOOT3_R ; B = SW_PVDDCR_CPU1_P1_BOOTR3

(kicad_pcb
	(version 20260206)
	(generator "pcbnew")
	(generator_version "10.0")
	(general
		(thickness 1.6)
		(legacy_teardrops no)
	)
	(paper "A4")
	(title_block
		(title "04192023_DAF0TMB3IC0_F0TG_MB_C_brd_V02_OCP.brd")
		(comment 1 "Grand Teton / footprints 4705-4706 of 8354")
	)
	(layers
		(0 "F.Cu" signal "TOP")
		(4 "In1.Cu" signal "GND")
		(6 "In2.Cu" signal "IN1")
		(8 "In3.Cu" signal "GND1")
		(10 "In4.Cu" signal "IN2")
		(12 "In5.Cu" signal "GND2")
		(14 "In6.Cu" signal "IN3")
		(16 "In7.Cu" signal "GND3")
		(18 "In8.Cu" signal "VCC")
		(20 "In9.Cu" signal "VCC1")
		(22 "In10.Cu" signal "GND4")
		(24 "In11.Cu" signal "IN4")
		(26 "In12.Cu" signal "GND5")
		(28 "In13.Cu" signal "IN5")
		(30 "In14.Cu" signal "GND6")
		(32 "In15.Cu" signal "IN6")
		(34 "In16.Cu" signal "GND7")
		(2 "B.Cu" signal "BOTTOM")
		(9 "F.Adhes" user "F.Adhesive")
		(11 "B.Adhes" user "B.Adhesive")
		(13 "F.Paste" user "Package Geometry/Pastemask Top")
		(15 "B.Paste" user "Package Geometry/Pastemask Bottom")
		(5 "F.SilkS" user "Ref Des/Silkscreen Top")
		(7 "B.SilkS" user "Ref Des/Silkscreen Bottom")
		(1 "F.Mask" user "Board Geometry/Soldermask Top")
		(3 "B.Mask" user "Board Geometry/Soldermask Bottom")
		(17 "Dwgs.User" user "User.Drawings")
		(19 "Cmts.User" user "User.Comments")
		(21 "Eco1.User" user "User.Eco1")
		(23 "Eco2.User" user "User.Eco2")
		(25 "Edge.Cuts" user "Board Geometry/Outline")
		(27 "Margin" user)
		(31 "F.CrtYd" user "Package Geometry/Place Bound Top")
		(29 "B.CrtYd" user "Package Geometry/Place Bound Bottom")
		(35 "F.Fab" user "Ref Des/Assembly Top")
		(33 "B.Fab" user "Ref Des/Assembly Bottom")
	)
	(footprint ""
		(layer "F.Cu")
		(at 72.194928 -339.651848 -90)
		(property "Reference" "PC414"
			(at 0 0 270)
			(layer "F.SilkS")
			(hide yes)
			(effects
				(font
					(size 1.27 1.27)
				)
			)
		)
		(property "Value" ""
			(at 0 0 270)
			(layer "F.Fab")
			(effects
				(font
					(size 1.27 1.27)
				)
			)
		)
		(duplicate_pad_numbers_are_jumpers no)
		(fp_line
			(start -0.7874 0.4064)
			(end -0.7874 -0.4064)
			(stroke
				(width 0.1524)
				(type default)
			)
			(layer "F.SilkS")
		)
		(fp_line
			(start 0.7874 0.4064)
			(end -0.7874 0.4064)
			(stroke
				(width 0.1524)
				(type default)
			)
			(layer "F.SilkS")
		)
		(fp_line
			(start -0.7874 -0.4064)
			(end 0.7874 -0.4064)
			(stroke
				(width 0.1524)
				(type default)
			)
			(layer "F.SilkS")
		)
		(fp_line
			(start 0.7874 -0.4064)
			(end 0.7874 0.4064)
			(stroke
				(width 0.1524)
				(type default)
			)
			(layer "F.SilkS")
		)
		(fp_line
			(start -0.67945 0.3048)
			(end -0.67945 -0.305054)
			(stroke
				(width 0.1)
				(type default)
			)
			(layer "F.Fab")
		)
		(fp_line
			(start -0.12065 0.3048)
			(end -0.67945 0.3048)
			(stroke
				(width 0.1)
				(type default)
			)
			(layer "F.Fab")
		)
		(fp_line
			(start 0.120396 0.3048)
			(end 0.120396 0.2794)
			(stroke
				(width 0.1)
				(type default)
			)
			(layer "F.Fab")
		)
		(fp_line
			(start 0.67945 0.3048)
			(end 0.120396 0.3048)
			(stroke
				(width 0.1)
				(type default)
			)
			(layer "F.Fab")
		)
		(fp_line
			(start -0.12065 0.2794)
			(end -0.12065 0.3048)
			(stroke
				(width 0.1)
				(type default)
			)
			(layer "F.Fab")
		)
		(fp_line
			(start 0.120396 0.2794)
			(end -0.12065 0.2794)
			(stroke
				(width 0.1)
				(type default)
			)
			(layer "F.Fab")
		)
		(fp_line
			(start -0.12065 -0.2794)
			(end 0.12065 -0.2794)
			(stroke
				(width 0.1)
				(type default)
			)
			(layer "F.Fab")
		)
		(fp_line
			(start 0.12065 -0.2794)
			(end 0.12065 -0.3048)
			(stroke
				(width 0.1)
				(type default)
			)
			(layer "F.Fab")
		)
		(fp_line
			(start 0.12065 -0.3048)
			(end 0.67945 -0.3048)
			(stroke
				(width 0.1)
				(type default)
			)
			(layer "F.Fab")
		)
		(fp_line
			(start 0.67945 -0.3048)
			(end 0.67945 0.3048)
			(stroke
				(width 0.1)
				(type default)
			)
			(layer "F.Fab")
		)
		(fp_line
			(start -0.67945 -0.305054)
			(end -0.12065 -0.305054)
			(stroke
				(width 0.1)
				(type default)
			)
			(layer "F.Fab")
		)
		(fp_line
			(start -0.12065 -0.305054)
			(end -0.12065 -0.2794)
			(stroke
				(width 0.1)
				(type default)
			)
			(layer "F.Fab")
		)
		(pad "1" smd circle
			(at -0.40005 0 270)
			(size 0 0)
			(layers "F.Cu" "F.Mask" "F.Paste")
			(net "SW_PVDDCR_CPU1_P1_BOOT3_R")
		)
		(pad "2" smd circle
			(at 0.40005 0 270)
			(size 0 0)
			(layers "F.Cu" "F.Mask" "F.Paste")
			(net "SW_PVDDCR_CPU1_P1_BOOTR3")
		)
	)
	(footprint ""
		(layer "F.Cu")
		(at 439.821066 -389.9535)
		(property "Reference" "PR6532"
			(at 0 0 0)
			(layer "F.SilkS")
			(hide yes)
			(effects
				(font
					(size 1.27 1.27)
				)
			)
		)
		(property "Value" ""
			(at 0 0 0)
			(layer "F.Fab")
			(effects
				(font
					(size 1.27 1.27)
				)
			)
		)
		(duplicate_pad_numbers_are_jumpers no)
		(fp_line
			(start -0.7874 -0.4064)
			(end 0.7874 -0.4064)
			(stroke
				(width 0.1524)
				(type default)
			)
			(layer "F.SilkS")
		)
		(fp_line
			(start -0.7874 0.4064)
			(end -0.7874 -0.4064)
			(stroke
				(width 0.1524)
				(type default)
			)
			(layer "F.SilkS")
		)
		(fp_line
			(start 0.7874 -0.4064)
			(end 0.7874 0.4064)
			(stroke
				(width 0.1524)
				(type default)
			)
			(layer "F.SilkS")
		)
		(fp_line
			(start 0.7874 0.4064)
			(end -0.7874 0.4064)
			(stroke
				(width 0.1524)
				(type default)
			)
			(layer "F.SilkS")
		)
		(fp_line
			(start -0.67945 -0.305054)
			(end -0.12065 -0.305054)
			(stroke
				(width 0.1)
				(type default)
			)
			(layer "F.Fab")
		)
		(fp_line
			(start -0.67945 0.3048)
			(end -0.67945 -0.305054)
			(stroke
				(width 0.1)
				(type default)
			)
			(layer "F.Fab")
		)
		(fp_line
			(start -0.12065 -0.305054)
			(end -0.12065 -0.2794)
			(stroke
				(width 0.1)
				(type default)
			)
			(layer "F.Fab")
		)
		(fp_line
			(start -0.12065 -0.2794)
			(end 0.12065 -0.2794)
			(stroke
				(width 0.1)
				(type default)
			)
			(layer "F.Fab")
		)
		(fp_line
			(start -0.12065 0.2794)
			(end -0.12065 0.3048)
			(stroke
				(width 0.1)
				(type default)
			)
			(layer "F.Fab")
		)
		(fp_line
			(start -0.12065 0.3048)
			(end -0.67945 0.3048)
			(stroke
				(width 0.1)
				(type default)
			)
			(layer "F.Fab")
		)
		(fp_line
			(start 0.120396 0.2794)
			(end -0.12065 0.2794)
			(stroke
				(width 0.1)
				(type default)
			)
			(layer "F.Fab")
		)
		(fp_line
			(start 0.120396 0.3048)
			(end 0.120396 0.2794)
			(stroke
				(width 0.1)
				(type default)
			)
			(layer "F.Fab")
		)
		(fp_line
			(start 0.12065 -0.3048)
			(end 0.67945 -0.3048)
			(stroke
				(width 0.1)
				(type default)
			)
			(layer "F.Fab")
		)
		(fp_line
			(start 0.12065 -0.2794)
			(end 0.12065 -0.3048)
			(stroke
				(width 0.1)
				(type default)
			)
			(layer "F.Fab")
		)
		(fp_line
			(start 0.67945 -0.3048)
			(end 0.67945 0.3048)
			(stroke
				(width 0.1)
				(type default)
			)
			(layer "F.Fab")
		)
		(fp_line
			(start 0.67945 0.3048)
			(end 0.120396 0.3048)
			(stroke
				(width 0.1)
				(type default)
			)
			(layer "F.Fab")
		)
		(pad "1" smd circle
			(at -0.40005 0)
			(size 0 0)
			(layers "F.Cu" "F.Mask" "F.Paste")
			(net "P0V9_RETIMER_CPU0_SENSE_SH_N")
		)
		(pad "2" smd circle
			(at 0.40005 0)
			(size 0 0)
			(layers "F.Cu" "F.Mask" "F.Paste")
			(net "GND")
		)
	)
)
